(kicad_pcb
	(version 20260206)
	(generator "pcbnew")
	(generator_version "10.0")
	(general
		(thickness 1.6)
		(legacy_teardrops no)
	)
	(paper "A4")
	(title_block
		(title "timecard-production-celestica-r4006 — R4006-B0001-02_R01.brd")
		(comment 1 "Time Appliance Project (Time Card) / footprints 727-732 of 1113")
	)
	(layers
		(0 "F.Cu" signal "TOP")
		(4 "In1.Cu" signal "L02_GND1")
		(6 "In2.Cu" signal "L03_SIG1")
		(8 "In3.Cu" signal "L04_GND2")
		(10 "In4.Cu" signal "L05_VCC1")
		(12 "In5.Cu" signal "L06_VCC2")
		(14 "In6.Cu" signal "L07_GND3")
		(16 "In7.Cu" signal "L08_SIG2")
		(18 "In8.Cu" signal "L09_GND4")
		(2 "B.Cu" signal "BOTTOM")
		(9 "F.Adhes" user "F.Adhesive")
		(11 "B.Adhes" user "B.Adhesive")
		(13 "F.Paste" user "Package Geometry/Pastemask Top")
		(15 "B.Paste" user "Package Geometry/Pastemask Bottom")
		(5 "F.SilkS" user "Ref Des/Silkscreen Top")
		(7 "B.SilkS" user "Ref Des/Silkscreen Bottom")
		(1 "F.Mask" user "Board Geometry/Soldermask Top")
		(3 "B.Mask" user "Board Geometry/Soldermask Bottom")
		(17 "Dwgs.User" user "User.Drawings")
		(19 "Cmts.User" user "User.Comments")
		(21 "Eco1.User" user "User.Eco1")
		(23 "Eco2.User" user "User.Eco2")
		(25 "Edge.Cuts" user "Board Geometry/Outline")
		(27 "Margin" user)
		(31 "F.CrtYd" user "Package Geometry/Place Bound Top")
		(29 "B.CrtYd" user "Package Geometry/Place Bound Bottom")
		(35 "F.Fab" user "Ref Des/Assembly Top")
		(33 "B.Fab" user "Ref Des/Assembly Bottom")
	)
	(footprint ""
		(layer "B.Cu")
		(at 114.847116 -35.322764 -90)
		(property "Reference" "C160"
			(at 0.778764 0.959866 270)
			(unlocked yes)
			(layer "B.SilkS")
			(effects
				(font
					(size 0.635 0.4064)
					(thickness 0.1524)
				)
				(justify mirror)
			)
		)
		(property "Value" "VAL*"
			(at 0 3.718306 270)
			(unlocked yes)
			(layer "B.Fab")
			(hide yes)
			(effects
				(font
					(size 0.7874 0.5842)
					(thickness 0.127)
				)
				(justify mirror)
			)
		)
		(property "Device Type" "CAPACITOR-G105-0F475-BM,4.7UF,A"
			(at 0 1.432306 270)
			(unlocked yes)
			(layer "B.Fab")
			(hide yes)
			(effects
				(font
					(size 0.7874 0.5842)
					(thickness 0.127)
				)
				(justify mirror)
			)
		)
		(property "User Part Number" "PARTNUM*"
			(at 0 2.575306 270)
			(unlocked yes)
			(layer "Cmts.User")
			(hide yes)
			(effects
				(font
					(size 0.7874 0.5842)
					(thickness 0.127)
				)
				(justify mirror)
			)
		)
		(property "Tolerance" "TOL*"
			(at 0 4.861306 270)
			(unlocked yes)
			(layer "Cmts.User")
			(hide yes)
			(effects
				(font
					(size 0.7874 0.5842)
					(thickness 0.127)
				)
				(justify mirror)
			)
		)
		(duplicate_pad_numbers_are_jumpers no)
		(fp_line
			(start -0.970026 0.4699)
			(end 0.970026 0.4699)
			(stroke
				(width 0.1)
				(type default)
			)
			(layer "B.SilkS")
		)
		(fp_line
			(start 0.970026 0.4699)
			(end 0.970026 -0.4699)
			(stroke
				(width 0.1)
				(type default)
			)
			(layer "B.SilkS")
		)
		(fp_line
			(start -0.970026 -0.4699)
			(end -0.970026 0.4699)
			(stroke
				(width 0.1)
				(type default)
			)
			(layer "B.SilkS")
		)
		(fp_line
			(start 0.970026 -0.4699)
			(end -0.970026 -0.4699)
			(stroke
				(width 0.1)
				(type default)
			)
			(layer "B.SilkS")
		)
		(fp_poly
			(pts
				(xy 0.970026 0.4699) (xy -0.970026 0.4699) (xy -0.970026 -0.4699) (xy 0.970026 -0.4699)
			)
			(stroke
				(width 0)
				(type default)
			)
			(fill no)
			(layer "B.CrtYd")
		)
		(fp_line
			(start -0.508 0.3048)
			(end 0.508 0.3048)
			(stroke
				(width 0.1)
				(type default)
			)
			(layer "B.Fab")
		)
		(fp_line
			(start 0.508 0.3048)
			(end 0.508 -0.3048)
			(stroke
				(width 0.1)
				(type default)
			)
			(layer "B.Fab")
		)
		(fp_line
			(start -0.508 -0.3048)
			(end -0.508 0.3048)
			(stroke
				(width 0.1)
				(type default)
			)
			(layer "B.Fab")
		)
		(fp_line
			(start 0.508 -0.3048)
			(end -0.508 -0.3048)
			(stroke
				(width 0.1)
				(type default)
			)
			(layer "B.Fab")
		)
		(pad "1" smd circle
			(at 0.500126 0 90)
			(size 0.635 0.635)
			(layers "B.Cu" "B.Mask" "B.Paste")
			(net "XP2R5V_FPGA")
		)
		(pad "2" smd circle
			(at -0.500126 0 90)
			(size 0.635 0.635)
			(layers "B.Cu" "B.Mask" "B.Paste")
			(net "SG")
		)
	)
	(footprint ""
		(layer "B.Cu")
		(at 29.845 -88.265 180)
		(property "Reference" "C95"
			(at -0.381 -1.30937 0)
			(unlocked yes)
			(layer "B.SilkS")
			(effects
				(font
					(size 0.7874 0.5842)
					(thickness 0.1524)
				)
				(justify mirror)
			)
		)
		(property "Value" "VAL*"
			(at -0.0762 2.067306 180)
			(unlocked yes)
			(layer "B.Fab")
			(hide yes)
			(effects
				(font
					(size 0.7874 0.5842)
					(thickness 0.1524)
				)
				(justify mirror)
			)
		)
		(property "Tolerance" "TOL*"
			(at -0.0762 3.032506 180)
			(unlocked yes)
			(layer "Cmts.User")
			(hide yes)
			(effects
				(font
					(size 0.7874 0.5842)
					(thickness 0.1524)
				)
				(justify mirror)
			)
		)
		(property "User Part Number" "PARTNUM*"
			(at -0.1016 4.023106 180)
			(unlocked yes)
			(layer "Cmts.User")
			(hide yes)
			(effects
				(font
					(size 0.7874 0.5842)
					(thickness 0.1524)
				)
				(justify mirror)
			)
		)
		(property "Device Type" "CAPACITOR-G105-0B104-CK,0.1UF,A"
			(at -0.0508 1.127506 180)
			(unlocked yes)
			(layer "B.Fab")
			(hide yes)
			(effects
				(font
					(size 0.7874 0.5842)
					(thickness 0.1524)
				)
				(justify mirror)
			)
		)
		(duplicate_pad_numbers_are_jumpers no)
		(fp_line
			(start 1.143 0.5588)
			(end -1.143 0.5588)
			(stroke
				(width 0.1)
				(type default)
			)
			(layer "B.SilkS")
		)
		(fp_line
			(start 1.143 -0.5588)
			(end 1.143 0.5588)
			(stroke
				(width 0.1)
				(type default)
			)
			(layer "B.SilkS")
		)
		(fp_line
			(start -1.143 0.5588)
			(end -1.143 -0.5588)
			(stroke
				(width 0.1)
				(type default)
			)
			(layer "B.SilkS")
		)
		(fp_line
			(start -1.143 -0.5588)
			(end 1.143 -0.5588)
			(stroke
				(width 0.1)
				(type default)
			)
			(layer "B.SilkS")
		)
		(fp_rect
			(start 1.143 -0.5588)
			(end -1.143 0.5588)
			(stroke
				(width 0)
				(type default)
			)
			(fill no)
			(layer "B.CrtYd")
		)
		(fp_line
			(start 0.508 0.3048)
			(end -0.508 0.3048)
			(stroke
				(width 0.1)
				(type default)
			)
			(layer "B.Fab")
		)
		(fp_line
			(start 0.508 -0.3048)
			(end 0.508 0.3048)
			(stroke
				(width 0.1)
				(type default)
			)
			(layer "B.Fab")
		)
		(fp_line
			(start -0.508 0.3048)
			(end -0.508 -0.3048)
			(stroke
				(width 0.1)
				(type default)
			)
			(layer "B.Fab")
		)
		(fp_line
			(start -0.508 -0.3048)
			(end 0.508 -0.3048)
			(stroke
				(width 0.1)
				(type default)
			)
			(layer "B.Fab")
		)
		(pad "1" smd rect
			(at 0.5334 0)
			(size 0.7112 0.6096)
			(layers "B.Cu" "B.Mask" "B.Paste")
			(net "XP3R3V_FT4232")
		)
		(pad "2" smd rect
			(at -0.5334 0)
			(size 0.7112 0.6096)
			(layers "B.Cu" "B.Mask" "B.Paste")
			(net "SG")
		)
		(zone
			(layer "B.Cu")
			(hatch none 0.5)
			(connect_pads
				(clearance 0)
			)
			(min_thickness 0.25)
			(keepout
				(tracks allowed)
				(vias not_allowed)
				(pads allowed)
				(copperpour not_allowed)
				(footprints allowed)
			)
			(placement
				(enabled no)
				(sheetname "")
			)
			(fill
				(thermal_gap 0.5)
				(thermal_bridge_width 0.5)
				(island_removal_mode 0)
			)
			(polygon
				(pts
					(xy 29.7688 -87.9602) (xy 29.9212 -87.9602) (xy 29.9212 -88.5698) (xy 29.7688 -88.5698)
				)
			)
		)
	)
	(footprint ""
		(layer "B.Cu")
		(at 104.847136 -42.323004 90)
		(property "Reference" "C222"
			(at -1.141984 -41.510966 270)
			(unlocked yes)
			(layer "B.SilkS")
			(effects
				(font
					(size 0.635 0.4064)
					(thickness 0.1524)
				)
				(justify mirror)
			)
		)
		(property "Value" "VAL*"
			(at 0 3.718306 90)
			(unlocked yes)
			(layer "B.Fab")
			(hide yes)
			(effects
				(font
					(size 0.7874 0.5842)
					(thickness 0.127)
				)
				(justify mirror)
			)
		)
		(property "Tolerance" "TOL*"
			(at 0 4.861306 90)
			(unlocked yes)
			(layer "Cmts.User")
			(hide yes)
			(effects
				(font
					(size 0.7874 0.5842)
					(thickness 0.127)
				)
				(justify mirror)
			)
		)
		(property "User Part Number" "PARTNUM*"
			(at 0 2.575306 90)
			(unlocked yes)
			(layer "Cmts.User")
			(hide yes)
			(effects
				(font
					(size 0.7874 0.5842)
					(thickness 0.127)
				)
				(justify mirror)
			)
		)
		(property "Device Type" "CAPACITOR-G105-0B104-CK,0.1UF,A"
			(at 0 1.432306 90)
			(unlocked yes)
			(layer "B.Fab")
			(hide yes)
			(effects
				(font
					(size 0.7874 0.5842)
					(thickness 0.127)
				)
				(justify mirror)
			)
		)
		(duplicate_pad_numbers_are_jumpers no)
		(fp_line
			(start 0.970026 -0.4699)
			(end -0.970026 -0.4699)
			(stroke
				(width 0.1)
				(type default)
			)
			(layer "B.SilkS")
		)
		(fp_line
			(start -0.970026 -0.4699)
			(end -0.970026 0.4699)
			(stroke
				(width 0.1)
				(type default)
			)
			(layer "B.SilkS")
		)
		(fp_line
			(start 0.970026 0.4699)
			(end 0.970026 -0.4699)
			(stroke
				(width 0.1)
				(type default)
			)
			(layer "B.SilkS")
		)
		(fp_line
			(start -0.970026 0.4699)
			(end 0.970026 0.4699)
			(stroke
				(width 0.1)
				(type default)
			)
			(layer "B.SilkS")
		)
		(fp_poly
			(pts
				(xy 0.970026 0.4699) (xy -0.970026 0.4699) (xy -0.970026 -0.4699) (xy 0.970026 -0.4699)
			)
			(stroke
				(width 0)
				(type default)
			)
			(fill no)
			(layer "B.CrtYd")
		)
		(fp_line
			(start 0.508 -0.3048)
			(end -0.508 -0.3048)
			(stroke
				(width 0.1)
				(type default)
			)
			(layer "B.Fab")
		)
		(fp_line
			(start -0.508 -0.3048)
			(end -0.508 0.3048)
			(stroke
				(width 0.1)
				(type default)
			)
			(layer "B.Fab")
		)
		(fp_line
			(start 0.508 0.3048)
			(end 0.508 -0.3048)
			(stroke
				(width 0.1)
				(type default)
			)
			(layer "B.Fab")
		)
		(fp_line
			(start -0.508 0.3048)
			(end 0.508 0.3048)
			(stroke
				(width 0.1)
				(type default)
			)
			(layer "B.Fab")
		)
		(pad "1" smd circle
			(at 0.500126 0 270)
			(size 0.635 0.635)
			(layers "B.Cu" "B.Mask" "B.Paste")
			(net "XP1R0V_FPGA_VCCINT")
		)
		(pad "2" smd circle
			(at -0.500126 0 270)
			(size 0.635 0.635)
			(layers "B.Cu" "B.Mask" "B.Paste")
			(net "SG")
		)
	)
	(footprint ""
		(layer "B.Cu")
		(at 39.6494 -95.9104)
		(property "Reference" "R49"
			(at 0.4826 1.20777 0)
			(unlocked yes)
			(layer "B.SilkS")
			(effects
				(font
					(size 0.7874 0.5842)
					(thickness 0.1524)
				)
				(justify mirror)
			)
		)
		(property "Value" "VAL*"
			(at -0.02032 2.13233 0)
			(unlocked yes)
			(layer "B.Fab")
			(hide yes)
			(effects
				(font
					(size 0.7874 0.5842)
					(thickness 0.1524)
				)
				(justify mirror)
			)
		)
		(property "Tolerance" "TOL*"
			(at -0.044704 3.05435 0)
			(unlocked yes)
			(layer "Cmts.User")
			(hide yes)
			(effects
				(font
					(size 0.7874 0.5842)
					(thickness 0.1524)
				)
				(justify mirror)
			)
		)
		(property "User Part Number" "PARTNUM*"
			(at -0.02032 4.024884 0)
			(unlocked yes)
			(layer "Cmts.User")
			(hide yes)
			(effects
				(font
					(size 0.7874 0.5842)
					(thickness 0.1524)
				)
				(justify mirror)
			)
		)
		(property "Device Type" "RESISTOR-G155-11002-01,10KOHM,A"
			(at -0.008382 1.210564 0)
			(unlocked yes)
			(layer "B.Fab")
			(hide yes)
			(effects
				(font
					(size 0.7874 0.5842)
					(thickness 0.1524)
				)
				(justify mirror)
			)
		)
		(duplicate_pad_numbers_are_jumpers no)
		(fp_line
			(start -1.143 -0.5588)
			(end 1.143 -0.5588)
			(stroke
				(width 0.1)
				(type default)
			)
			(layer "B.SilkS")
		)
		(fp_line
			(start -1.143 0.5588)
			(end -1.143 -0.5588)
			(stroke
				(width 0.1)
				(type default)
			)
			(layer "B.SilkS")
		)
		(fp_line
			(start 1.143 -0.5588)
			(end 1.143 0.5588)
			(stroke
				(width 0.1)
				(type default)
			)
			(layer "B.SilkS")
		)
		(fp_line
			(start 1.143 0.5588)
			(end -1.143 0.5588)
			(stroke
				(width 0.1)
				(type default)
			)
			(layer "B.SilkS")
		)
		(fp_poly
			(pts
				(xy 1.143 0.5588) (xy -1.143 0.5588) (xy -1.143 -0.5588) (xy 1.143 -0.5588)
			)
			(stroke
				(width 0)
				(type default)
			)
			(fill no)
			(layer "B.CrtYd")
		)
		(fp_line
			(start -0.508 -0.3048)
			(end 0.508 -0.3048)
			(stroke
				(width 0.1)
				(type default)
			)
			(layer "B.Fab")
		)
		(fp_line
			(start -0.508 0.3048)
			(end -0.508 -0.3048)
			(stroke
				(width 0.1)
				(type default)
			)
			(layer "B.Fab")
		)
		(fp_line
			(start 0.508 -0.3048)
			(end 0.508 0.3048)
			(stroke
				(width 0.1)
				(type default)
			)
			(layer "B.Fab")
		)
		(fp_line
			(start 0.508 0.3048)
			(end -0.508 0.3048)
			(stroke
				(width 0.1)
				(type default)
			)
			(layer "B.Fab")
		)
		(pad "1" smd rect
			(at 0.5334 0 180)
			(size 0.7112 0.6096)
			(layers "B.Cu" "B.Mask" "B.Paste")
			(net "VIN_XP5R0V")
		)
		(pad "2" smd rect
			(at -0.5334 0 180)
			(size 0.7112 0.6096)
			(layers "B.Cu" "B.Mask" "B.Paste")
			(net "R_XP5R0V_EN")
		)
		(zone
			(layer "B.Cu")
			(hatch none 0.5)
			(connect_pads
				(clearance 0)
			)
			(min_thickness 0.25)
			(keepout
				(tracks not_allowed)
				(vias allowed)
				(pads allowed)
				(copperpour not_allowed)
				(footprints allowed)
			)
			(placement
				(enabled no)
				(sheetname "")
			)
			(fill
				(thermal_gap 0.5)
				(thermal_bridge_width 0.5)
				(island_removal_mode 0)
			)
			(polygon
				(pts
					(xy 39.7256 -95.6056) (xy 39.7256 -96.2152) (xy 39.5732 -96.2152) (xy 39.5732 -95.6056)
				)
			)
		)
		(zone
			(layer "B.Cu")
			(hatch none 0.5)
			(connect_pads
				(clearance 0)
			)
			(min_thickness 0.25)
			(keepout
				(tracks allowed)
				(vias not_allowed)
				(pads allowed)
				(copperpour not_allowed)
				(footprints allowed)
			)
			(placement
				(enabled no)
				(sheetname "")
			)
			(fill
				(thermal_gap 0.5)
				(thermal_bridge_width 0.5)
				(island_removal_mode 0)
			)
			(polygon
				(pts
					(xy 39.7256 -95.6056) (xy 39.7256 -96.2152) (xy 39.5732 -96.2152) (xy 39.5732 -95.6056)
				)
			)
		)
	)
	(footprint ""
		(layer "B.Cu")
		(at 116.847112 -39.323264 -90)
		(property "Reference" "C93"
			(at -0.173736 0.927862 270)
			(unlocked yes)
			(layer "B.SilkS")
			(effects
				(font
					(size 0.635 0.4064)
					(thickness 0.1524)
				)
				(justify mirror)
			)
		)
		(property "Value" "VAL*"
			(at 0 3.718306 270)
			(unlocked yes)
			(layer "B.Fab")
			(hide yes)
			(effects
				(font
					(size 0.7874 0.5842)
					(thickness 0.127)
				)
				(justify mirror)
			)
		)
		(property "Tolerance" "TOL*"
			(at 0 4.861306 270)
			(unlocked yes)
			(layer "Cmts.User")
			(hide yes)
			(effects
				(font
					(size 0.7874 0.5842)
					(thickness 0.127)
				)
				(justify mirror)
			)
		)
		(property "User Part Number" "PARTNUM*"
			(at 0 2.575306 270)
			(unlocked yes)
			(layer "Cmts.User")
			(hide yes)
			(effects
				(font
					(size 0.7874 0.5842)
					(thickness 0.127)
				)
				(justify mirror)
			)
		)
		(property "Device Type" "CAPACITOR-G105-0F475-BM,4.7UF,A"
			(at 0 1.432306 270)
			(unlocked yes)
			(layer "B.Fab")
			(hide yes)
			(effects
				(font
					(size 0.7874 0.5842)
					(thickness 0.127)
				)
				(justify mirror)
			)
		)
		(duplicate_pad_numbers_are_jumpers no)
		(fp_line
			(start -0.970026 0.4699)
			(end 0.970026 0.4699)
			(stroke
				(width 0.1)
				(type default)
			)
			(layer "B.SilkS")
		)
		(fp_line
			(start 0.970026 0.4699)
			(end 0.970026 -0.4699)
			(stroke
				(width 0.1)
				(type default)
			)
			(layer "B.SilkS")
		)
		(fp_line
			(start -0.970026 -0.4699)
			(end -0.970026 0.4699)
			(stroke
				(width 0.1)
				(type default)
			)
			(layer "B.SilkS")
		)
		(fp_line
			(start 0.970026 -0.4699)
			(end -0.970026 -0.4699)
			(stroke
				(width 0.1)
				(type default)
			)
			(layer "B.SilkS")
		)
		(fp_poly
			(pts
				(xy 0.970026 0.4699) (xy -0.970026 0.4699) (xy -0.970026 -0.4699) (xy 0.970026 -0.4699)
			)
			(stroke
				(width 0)
				(type default)
			)
			(fill no)
			(layer "B.CrtYd")
		)
		(fp_line
			(start -0.508 0.3048)
			(end 0.508 0.3048)
			(stroke
				(width 0.1)
				(type default)
			)
			(layer "B.Fab")
		)
		(fp_line
			(start 0.508 0.3048)
			(end 0.508 -0.3048)
			(stroke
				(width 0.1)
				(type default)
			)
			(layer "B.Fab")
		)
		(fp_line
			(start -0.508 -0.3048)
			(end -0.508 0.3048)
			(stroke
				(width 0.1)
				(type default)
			)
			(layer "B.Fab")
		)
		(fp_line
			(start 0.508 -0.3048)
			(end -0.508 -0.3048)
			(stroke
				(width 0.1)
				(type default)
			)
			(layer "B.Fab")
		)
		(pad "1" smd circle
			(at 0.500126 0 90)
			(size 0.635 0.635)
			(layers "B.Cu" "B.Mask" "B.Paste")
			(net "XP2R5V_FPGA")
		)
		(pad "2" smd circle
			(at -0.500126 0 90)
			(size 0.635 0.635)
			(layers "B.Cu" "B.Mask" "B.Paste")
			(net "SG")
		)
	)
	(footprint ""
		(layer "B.Cu")
		(at 128.1938 -62.3316 180)
		(property "Reference" "C181"
			(at 0.8128 1.76403 0)
			(unlocked yes)
			(layer "B.SilkS")
			(effects
				(font
					(size 0.7874 0.5842)
					(thickness 0.1524)
				)
				(justify mirror)
			)
		)
		(property "Value" "VAL*"
			(at -0.0762 3.134106 180)
			(unlocked yes)
			(layer "B.Fab")
			(hide yes)
			(effects
				(font
					(size 0.7874 0.5842)
					(thickness 0.1524)
				)
				(justify mirror)
			)
		)
		(property "Tolerance" "TOL*"
			(at -0.0762 4.048506 180)
			(unlocked yes)
			(layer "Cmts.User")
			(hide yes)
			(effects
				(font
					(size 0.7874 0.5842)
					(thickness 0.1524)
				)
				(justify mirror)
			)
		)
		(property "User Part Number" "PARTNUM*"
			(at -0.1016 5.013706 180)
			(unlocked yes)
			(layer "Cmts.User")
			(hide yes)
			(effects
				(font
					(size 0.7874 0.5842)
					(thickness 0.1524)
				)
				(justify mirror)
			)
		)
		(property "Device Type" "CAPACITOR-G107-0F226-CM,22UF,2A"
			(at -0.0508 2.194306 180)
			(unlocked yes)
			(layer "B.Fab")
			(hide yes)
			(effects
				(font
					(size 0.7874 0.5842)
					(thickness 0.1524)
				)
				(justify mirror)
			)
		)
		(duplicate_pad_numbers_are_jumpers no)
		(fp_line
			(start 1.5748 0.9398)
			(end -1.5748 0.9398)
			(stroke
				(width 0.1)
				(type default)
			)
			(layer "B.SilkS")
		)
		(fp_line
			(start 1.5748 -0.9398)
			(end 1.5748 0.9398)
			(stroke
				(width 0.1)
				(type default)
			)
			(layer "B.SilkS")
		)
		(fp_line
			(start -1.5748 0.9398)
			(end -1.5748 -0.9398)
			(stroke
				(width 0.1)
				(type default)
			)
			(layer "B.SilkS")
		)
		(fp_line
			(start -1.5748 -0.9398)
			(end 1.5748 -0.9398)
			(stroke
				(width 0.1)
				(type default)
			)
			(layer "B.SilkS")
		)
		(fp_rect
			(start -1.5748 0.9398)
			(end 1.5748 -0.9398)
			(stroke
				(width 0)
				(type default)
			)
			(fill no)
			(layer "B.CrtYd")
		)
		(fp_line
			(start 1.016 0.635)
			(end -1.016 0.635)
			(stroke
				(width 0.1)
				(type default)
			)
			(layer "B.Fab")
		)
		(fp_line
			(start 1.016 -0.635)
			(end 1.016 0.635)
			(stroke
				(width 0.1)
				(type default)
			)
			(layer "B.Fab")
		)
		(fp_line
			(start -1.016 0.635)
			(end -1.016 -0.635)
			(stroke
				(width 0.1)
				(type default)
			)
			(layer "B.Fab")
		)
		(fp_line
			(start -1.016 -0.635)
			(end 1.016 -0.635)
			(stroke
				(width 0.1)
				(type default)
			)
			(layer "B.Fab")
		)
		(pad "1" smd rect
			(at 0.8382 0)
			(size 0.9652 1.3716)
			(layers "B.Cu" "B.Mask" "B.Paste")
			(net "XP3R3V")
		)
		(pad "2" smd rect
			(at -0.8382 0)
			(size 0.9652 1.3716)
			(layers "B.Cu" "B.Mask" "B.Paste")
			(net "SG")
		)
		(zone
			(layer "B.Cu")
			(hatch none 0.5)
			(connect_pads
				(clearance 0)
			)
			(min_thickness 0.25)
			(keepout
				(tracks allowed)
				(vias not_allowed)
				(pads allowed)
				(copperpour not_allowed)
				(footprints allowed)
			)
			(placement
				(enabled no)
				(sheetname "")
			)
			(fill
				(thermal_gap 0.5)
				(thermal_bridge_width 0.5)
				(island_removal_mode 0)
			)
			(polygon
				(pts
					(xy 128.4224 -62.9666) (xy 127.9652 -62.9666) (xy 127.9652 -61.6966) (xy 128.4224 -61.6966)
				)
			)
		)
	)
)
